# T6G (Grand Teton) — schematic netlist excerpt (pin names and nets, part order shuffled) for the footprints in the layout excerpt that follows; sources: Cadence DE-HDL packaged netlist, KiCad conversion of 04192023_DAF0TMB3IC0_F0TG_MB_C_brd_V02_OCP.brd

C2183  Q_CAP  22UF 4V 20% X6S  pkg C0402  page 69 : A = PVDDCR_CPU0_P0 ; B = GND
C601  Q_CAP  0.1UF 10V 10% X7S  pkg C0201  page 290 : A = P1V8_CPU0_RT1_1A_1D ; B = GND
R1801  Q_RES  0 5% CHIP  pkg 0402LF  page 150 : A = PRSNT0_N ; B = GND

(kicad_pcb
	(version 20260206)
	(generator "pcbnew")
	(generator_version "10.0")
	(general
		(thickness 1.6)
		(legacy_teardrops no)
	)
	(paper "A4")
	(title_block
		(title "04192023_DAF0TMB3IC0_F0TG_MB_C_brd_V02_OCP.brd")
		(comment 1 "Grand Teton / footprints 6735-6737 of 8354")
	)
	(layers
		(0 "F.Cu" signal "TOP")
		(4 "In1.Cu" signal "GND")
		(6 "In2.Cu" signal "IN1")
		(8 "In3.Cu" signal "GND1")
		(10 "In4.Cu" signal "IN2")
		(12 "In5.Cu" signal "GND2")
		(14 "In6.Cu" signal "IN3")
		(16 "In7.Cu" signal "GND3")
		(18 "In8.Cu" signal "VCC")
		(20 "In9.Cu" signal "VCC1")
		(22 "In10.Cu" signal "GND4")
		(24 "In11.Cu" signal "IN4")
		(26 "In12.Cu" signal "GND5")
		(28 "In13.Cu" signal "IN5")
		(30 "In14.Cu" signal "GND6")
		(32 "In15.Cu" signal "IN6")
		(34 "In16.Cu" signal "GND7")
		(2 "B.Cu" signal "BOTTOM")
		(9 "F.Adhes" user "F.Adhesive")
		(11 "B.Adhes" user "B.Adhesive")
		(13 "F.Paste" user "Package Geometry/Pastemask Top")
		(15 "B.Paste" user "Package Geometry/Pastemask Bottom")
		(5 "F.SilkS" user "Ref Des/Silkscreen Top")
		(7 "B.SilkS" user "Ref Des/Silkscreen Bottom")
		(1 "F.Mask" user "Board Geometry/Soldermask Top")
		(3 "B.Mask" user "Board Geometry/Soldermask Bottom")
		(17 "Dwgs.User" user "User.Drawings")
		(19 "Cmts.User" user "User.Comments")
		(21 "Eco1.User" user "User.Eco1")
		(23 "Eco2.User" user "User.Eco2")
		(25 "Edge.Cuts" user "Board Geometry/Outline")
		(27 "Margin" user)
		(31 "F.CrtYd" user "Package Geometry/Place Bound Top")
		(29 "B.CrtYd" user "Package Geometry/Place Bound Bottom")
		(35 "F.Fab" user "Ref Des/Assembly Top")
		(33 "B.Fab" user "Ref Des/Assembly Bottom")
	)
	(footprint ""
		(layer "B.Cu")
		(at 347.897958 -245.868952 -90)
		(property "Reference" "C2183"
			(at 0 0 90)
			(layer "B.SilkS")
			(hide yes)
			(effects
				(font
					(size 1.27 1.27)
				)
				(justify mirror)
			)
		)
		(property "Value" ""
			(at 0 0 90)
			(layer "B.Fab")
			(effects
				(font
					(size 1.27 1.27)
				)
				(justify mirror)
			)
		)
		(duplicate_pad_numbers_are_jumpers no)
		(fp_line
			(start -0.7874 0.4064)
			(end 0.7874 0.4064)
			(stroke
				(width 0.1524)
				(type default)
			)
			(layer "B.SilkS")
		)
		(fp_line
			(start 0.7874 0.4064)
			(end 0.7874 -0.4064)
			(stroke
				(width 0.1524)
				(type default)
			)
			(layer "B.SilkS")
		)
		(fp_line
			(start -0.7874 -0.4064)
			(end -0.7874 0.4064)
			(stroke
				(width 0.1524)
				(type default)
			)
			(layer "B.SilkS")
		)
		(fp_line
			(start 0.7874 -0.4064)
			(end -0.7874 -0.4064)
			(stroke
				(width 0.1524)
				(type default)
			)
			(layer "B.SilkS")
		)
		(fp_line
			(start -0.67945 0.3048)
			(end -0.120396 0.3048)
			(stroke
				(width 0.1)
				(type default)
			)
			(layer "B.Fab")
		)
		(fp_line
			(start -0.120396 0.3048)
			(end -0.120396 0.2794)
			(stroke
				(width 0.1)
				(type default)
			)
			(layer "B.Fab")
		)
		(fp_line
			(start 0.12065 0.3048)
			(end 0.67945 0.3048)
			(stroke
				(width 0.1)
				(type default)
			)
			(layer "B.Fab")
		)
		(fp_line
			(start 0.67945 0.3048)
			(end 0.67945 -0.305054)
			(stroke
				(width 0.1)
				(type default)
			)
			(layer "B.Fab")
		)
		(fp_line
			(start -0.120396 0.2794)
			(end 0.12065 0.2794)
			(stroke
				(width 0.1)
				(type default)
			)
			(layer "B.Fab")
		)
		(fp_line
			(start 0.12065 0.2794)
			(end 0.12065 0.3048)
			(stroke
				(width 0.1)
				(type default)
			)
			(layer "B.Fab")
		)
		(fp_line
			(start -0.12065 -0.2794)
			(end -0.12065 -0.3048)
			(stroke
				(width 0.1)
				(type default)
			)
			(layer "B.Fab")
		)
		(fp_line
			(start 0.12065 -0.2794)
			(end -0.12065 -0.2794)
			(stroke
				(width 0.1)
				(type default)
			)
			(layer "B.Fab")
		)
		(fp_line
			(start -0.67945 -0.3048)
			(end -0.67945 0.3048)
			(stroke
				(width 0.1)
				(type default)
			)
			(layer "B.Fab")
		)
		(fp_line
			(start -0.12065 -0.3048)
			(end -0.67945 -0.3048)
			(stroke
				(width 0.1)
				(type default)
			)
			(layer "B.Fab")
		)
		(fp_line
			(start 0.12065 -0.305054)
			(end 0.12065 -0.2794)
			(stroke
				(width 0.1)
				(type default)
			)
			(layer "B.Fab")
		)
		(fp_line
			(start 0.67945 -0.305054)
			(end 0.12065 -0.305054)
			(stroke
				(width 0.1)
				(type default)
			)
			(layer "B.Fab")
		)
		(pad "1" smd circle
			(at 0.40005 0 90)
			(size 0 0)
			(layers "B.Cu" "B.Mask" "B.Paste")
			(net "PVDDCR_CPU0_P0")
		)
		(pad "2" smd circle
			(at -0.40005 0 90)
			(size 0 0)
			(layers "B.Cu" "B.Mask" "B.Paste")
			(net "GND")
		)
	)
	(footprint ""
		(layer "B.Cu")
		(at 190.668402 -19.311366 180)
		(property "Reference" "R1801"
			(at 0 0 0)
			(layer "B.SilkS")
			(hide yes)
			(effects
				(font
					(size 1.27 1.27)
				)
				(justify mirror)
			)
		)
		(property "Value" ""
			(at 0 0 0)
			(layer "B.Fab")
			(effects
				(font
					(size 1.27 1.27)
				)
				(justify mirror)
			)
		)
		(duplicate_pad_numbers_are_jumpers no)
		(fp_line
			(start 0.7874 0.4064)
			(end 0.7874 -0.4064)
			(stroke
				(width 0.1524)
				(type default)
			)
			(layer "B.SilkS")
		)
		(fp_line
			(start 0.7874 -0.4064)
			(end -0.7874 -0.4064)
			(stroke
				(width 0.1524)
				(type default)
			)
			(layer "B.SilkS")
		)
		(fp_line
			(start -0.7874 0.4064)
			(end 0.7874 0.4064)
			(stroke
				(width 0.1524)
				(type default)
			)
			(layer "B.SilkS")
		)
		(fp_line
			(start -0.7874 -0.4064)
			(end -0.7874 0.4064)
			(stroke
				(width 0.1524)
				(type default)
			)
			(layer "B.SilkS")
		)
		(fp_line
			(start 0.67945 0.3048)
			(end 0.67945 -0.305054)
			(stroke
				(width 0.1)
				(type default)
			)
			(layer "B.Fab")
		)
		(fp_line
			(start 0.67945 -0.305054)
			(end 0.12065 -0.305054)
			(stroke
				(width 0.1)
				(type default)
			)
			(layer "B.Fab")
		)
		(fp_line
			(start 0.12065 0.3048)
			(end 0.67945 0.3048)
			(stroke
				(width 0.1)
				(type default)
			)
			(layer "B.Fab")
		)
		(fp_line
			(start 0.12065 0.2794)
			(end 0.12065 0.3048)
			(stroke
				(width 0.1)
				(type default)
			)
			(layer "B.Fab")
		)
		(fp_line
			(start 0.12065 -0.2794)
			(end -0.12065 -0.2794)
			(stroke
				(width 0.1)
				(type default)
			)
			(layer "B.Fab")
		)
		(fp_line
			(start 0.12065 -0.305054)
			(end 0.12065 -0.2794)
			(stroke
				(width 0.1)
				(type default)
			)
			(layer "B.Fab")
		)
		(fp_line
			(start -0.120396 0.3048)
			(end -0.120396 0.2794)
			(stroke
				(width 0.1)
				(type default)
			)
			(layer "B.Fab")
		)
		(fp_line
			(start -0.120396 0.2794)
			(end 0.12065 0.2794)
			(stroke
				(width 0.1)
				(type default)
			)
			(layer "B.Fab")
		)
		(fp_line
			(start -0.12065 -0.2794)
			(end -0.12065 -0.3048)
			(stroke
				(width 0.1)
				(type default)
			)
			(layer "B.Fab")
		)
		(fp_line
			(start -0.12065 -0.3048)
			(end -0.67945 -0.3048)
			(stroke
				(width 0.1)
				(type default)
			)
			(layer "B.Fab")
		)
		(fp_line
			(start -0.67945 0.3048)
			(end -0.120396 0.3048)
			(stroke
				(width 0.1)
				(type default)
			)
			(layer "B.Fab")
		)
		(fp_line
			(start -0.67945 -0.3048)
			(end -0.67945 0.3048)
			(stroke
				(width 0.1)
				(type default)
			)
			(layer "B.Fab")
		)
		(pad "1" smd circle
			(at 0.40005 0)
			(size 0 0)
			(layers "B.Cu" "B.Mask" "B.Paste")
			(net "PRSNT0_N")
		)
		(pad "2" smd circle
			(at -0.40005 0)
			(size 0 0)
			(layers "B.Cu" "B.Mask" "B.Paste")
			(net "GND")
		)
	)
	(footprint ""
		(layer "B.Cu")
		(at 346.84589 -396.393162 -90)
		(property "Reference" "C601"
			(at 0 0 90)
			(layer "B.SilkS")
			(hide yes)
			(effects
				(font
					(size 1.27 1.27)
				)
				(justify mirror)
			)
		)
		(property "Value" ""
			(at 0 0 90)
			(layer "B.Fab")
			(effects
				(font
					(size 1.27 1.27)
				)
				(justify mirror)
			)
		)
		(duplicate_pad_numbers_are_jumpers no)
		(fp_line
			(start -0.299974 0.150114)
			(end 0.299974 0.150114)
			(stroke
				(width 0.1)
				(type default)
			)
			(layer "B.Fab")
		)
		(fp_line
			(start 0.299974 0.150114)
			(end 0.299974 -0.150114)
			(stroke
				(width 0.1)
				(type default)
			)
			(layer "B.Fab")
		)
		(fp_line
			(start -0.299974 -0.150114)
			(end -0.299974 0.150114)
			(stroke
				(width 0.1)
				(type default)
			)
			(layer "B.Fab")
		)
		(fp_line
			(start 0.299974 -0.150114)
			(end -0.299974 -0.150114)
			(stroke
				(width 0.1)
				(type default)
			)
			(layer "B.Fab")
		)
		(pad "1" smd rect
			(at 0.2667 0 90)
			(size 0.3048 0.381)
			(layers "B.Cu" "B.Mask" "B.Paste")
			(net "P1V8_CPU0_RT1_1A_1D")
		)
		(pad "2" smd rect
			(at -0.2667 0 90)
			(size 0.3048 0.381)
			(layers "B.Cu" "B.Mask" "B.Paste")
			(net "GND")
		)
	)
)
